(kicad_pcb
	(version 20241229)
	(generator "pcbnew")
	(generator_version "9.0")
	(general
		(thickness 1.294)
		(legacy_teardrops no)
	)
	(paper "A3")
	(title_block
		(title "Kintex 410T devboard")
		(date "2024-04-03")
		(rev "1.1.2")
		(comment 9 "footprints 545-550 of 975")
	)
	(layers
		(0 "F.Cu" mixed)
		(4 "In1.Cu" power)
		(6 "In2.Cu" power)
		(8 "In3.Cu" mixed)
		(10 "In4.Cu" power)
		(12 "In5.Cu" mixed)
		(14 "In6.Cu" power)
		(16 "In7.Cu" mixed)
		(18 "In8.Cu" power)
		(2 "B.Cu" mixed)
		(9 "F.Adhes" user "F.Adhesive")
		(11 "B.Adhes" user "B.Adhesive")
		(13 "F.Paste" user)
		(15 "B.Paste" user)
		(5 "F.SilkS" user "F.Silkscreen")
		(7 "B.SilkS" user "B.Silkscreen")
		(1 "F.Mask" user)
		(3 "B.Mask" user)
		(17 "Dwgs.User" user "User.Drawings")
		(19 "Cmts.User" user "User.Comments")
		(21 "Eco1.User" user "User.Eco1")
		(23 "Eco2.User" user "User.Eco2")
		(25 "Edge.Cuts" user)
		(27 "Margin" user)
		(31 "F.CrtYd" user "F.Courtyard")
		(29 "B.CrtYd" user "B.Courtyard")
		(35 "F.Fab" user)
		(33 "B.Fab" user)
	)
	(footprint "antmicro-footprints:C_0402_1005Metric"
		(layer "B.Cu")
		(at 174.499999 147.999999 -90)
		(descr "Capacitor SMD 0402")
		(tags "capacitor SMD 0402")
		(property "Reference" "C183"
			(at 0.775001 -0.400001 90)
			(layer "B.SilkS")
			(effects
				(font
					(size 0.7 0.7)
					(thickness 0.15)
				)
				(justify left bottom mirror)
			)
		)
		(property "Value" "C_100n_0402"
			(at 0 -1.169 90)
			(layer "B.Fab")
			(effects
				(font
					(size 0.7 0.7)
					(thickness 0.15)
				)
				(justify left bottom mirror)
			)
		)
		(property "Description" "SMD Multilayer Ceramic Capacitor, 0.1 µF, 50 V, 0402 [1005 Metric], ± 10%, X5R, GRM Series"
			(at 0 0 270)
			(layer "F.Fab")
			(hide yes)
			(effects
				(font
					(size 1.27 1.27)
					(thickness 0.15)
				)
			)
		)
		(property "Author" "Antmicro"
			(at 26.5 322.499998 0)
			(layer "B.Fab")
			(hide yes)
			(effects
				(font
					(size 1 1)
					(thickness 0.15)
				)
				(justify mirror)
			)
		)
		(property "Dielectric" "X5R"
			(at 26.5 322.499998 0)
			(layer "B.Fab")
			(hide yes)
			(effects
				(font
					(size 1 1)
					(thickness 0.15)
				)
				(justify mirror)
			)
		)
		(property "License" "Apache-2.0"
			(at 26.5 322.499998 0)
			(layer "B.Fab")
			(hide yes)
			(effects
				(font
					(size 1 1)
					(thickness 0.15)
				)
				(justify mirror)
			)
		)
		(property "MPN" "GRM155R61H104KE14D"
			(at 26.5 322.499998 0)
			(layer "B.Fab")
			(hide yes)
			(effects
				(font
					(size 1 1)
					(thickness 0.15)
				)
				(justify mirror)
			)
		)
		(property "Manufacturer" "Murata"
			(at 26.5 322.499998 0)
			(layer "B.Fab")
			(hide yes)
			(effects
				(font
					(size 1 1)
					(thickness 0.15)
				)
				(justify mirror)
			)
		)
		(property "Val" "100n"
			(at 26.5 322.499998 0)
			(layer "B.Fab")
			(hide yes)
			(effects
				(font
					(size 1 1)
					(thickness 0.15)
				)
				(justify mirror)
			)
		)
		(property "Voltage" "50V"
			(at 26.5 322.499998 0)
			(layer "B.Fab")
			(hide yes)
			(effects
				(font
					(size 1 1)
					(thickness 0.15)
				)
				(justify mirror)
			)
		)
		(sheetname "DRAM + SRAM")
		(sheetfile "ram.kicad_sch")
		(attr smd)
		(fp_rect
			(start -0.925 0.47)
			(end 0.925 -0.47)
			(stroke
				(width 0.05)
				(type default)
			)
			(fill no)
			(layer "B.CrtYd")
		)
		(fp_line
			(start -0.494 0.25)
			(end 0.504 0.25)
			(stroke
				(width 0.15)
				(type solid)
			)
			(layer "B.Fab")
		)
		(fp_line
			(start 0.504 0.25)
			(end 0.504 -0.248)
			(stroke
				(width 0.15)
				(type solid)
			)
			(layer "B.Fab")
		)
		(fp_line
			(start -0.494 -0.248)
			(end -0.494 0.25)
			(stroke
				(width 0.15)
				(type solid)
			)
			(layer "B.Fab")
		)
		(fp_line
			(start 0.504 -0.248)
			(end -0.494 -0.248)
			(stroke
				(width 0.15)
				(type solid)
			)
			(layer "B.Fab")
		)
		(pad "1" smd roundrect
			(at -0.48 0 270)
			(size 0.59 0.64)
			(layers "B.Cu" "B.Mask" "B.Paste")
			(roundrect_rratio 0.25)
			(net 1 "GND")
			(pintype "passive")
		)
		(pad "2" smd roundrect
			(at 0.48 0 270)
			(size 0.59 0.64)
			(layers "B.Cu" "B.Mask" "B.Paste")
			(roundrect_rratio 0.25)
			(net 25 "+1V35")
			(pintype "passive")
		)
	)
	(footprint "antmicro-footprints:C_0402_1005Metric"
		(layer "B.Cu")
		(at 228.1 165.4 90)
		(descr "Capacitor SMD 0402")
		(tags "capacitor SMD 0402")
		(property "Reference" "C192"
			(at 3.675 0.375 270)
			(layer "B.SilkS")
			(effects
				(font
					(size 0.7 0.7)
					(thickness 0.15)
				)
				(justify left bottom mirror)
			)
		)
		(property "Value" "C_1u_0402"
			(at 0 -1.4 270)
			(layer "B.Fab")
			(effects
				(font
					(size 0.7 0.7)
					(thickness 0.15)
				)
				(justify left bottom mirror)
			)
		)
		(property "Description" "SMD Multilayer Ceramic Capacitor, 1 µF, 10 V, 0402 [1005 Metric], ± 10%, X6S, C"
			(at 0 0 90)
			(layer "F.Fab")
			(hide yes)
			(effects
				(font
					(size 1.27 1.27)
					(thickness 0.15)
				)
			)
		)
		(property "Author" "Antmicro"
			(at 393.5 -62.7 0)
			(layer "B.Fab")
			(hide yes)
			(effects
				(font
					(size 1 1)
					(thickness 0.15)
				)
				(justify mirror)
			)
		)
		(property "Dielectric" ""
			(at 393.5 -62.7 0)
			(layer "B.Fab")
			(hide yes)
			(effects
				(font
					(size 1 1)
					(thickness 0.15)
				)
				(justify mirror)
			)
		)
		(property "License" "Apache-2.0"
			(at 393.5 -62.7 0)
			(layer "B.Fab")
			(hide yes)
			(effects
				(font
					(size 1 1)
					(thickness 0.15)
				)
				(justify mirror)
			)
		)
		(property "MPN" "C1005X6S1A105K050BC"
			(at 393.5 -62.7 0)
			(layer "B.Fab")
			(hide yes)
			(effects
				(font
					(size 1 1)
					(thickness 0.15)
				)
				(justify mirror)
			)
		)
		(property "Manufacturer" "TDK"
			(at 393.5 -62.7 0)
			(layer "B.Fab")
			(hide yes)
			(effects
				(font
					(size 1 1)
					(thickness 0.15)
				)
				(justify mirror)
			)
		)
		(property "Val" "1u"
			(at 393.5 -62.7 0)
			(layer "B.Fab")
			(hide yes)
			(effects
				(font
					(size 1 1)
					(thickness 0.15)
				)
				(justify mirror)
			)
		)
		(property "Voltage" ""
			(at 393.5 -62.7 0)
			(layer "B.Fab")
			(hide yes)
			(effects
				(font
					(size 1 1)
					(thickness 0.15)
				)
				(justify mirror)
			)
		)
		(sheetname "Power supply")
		(sheetfile "power-supply.kicad_sch")
		(attr smd)
		(fp_rect
			(start -0.925 0.47)
			(end 0.925 -0.47)
			(stroke
				(width 0.05)
				(type default)
			)
			(fill no)
			(layer "B.CrtYd")
		)
		(fp_line
			(start 0.504 -0.248)
			(end -0.494 -0.248)
			(stroke
				(width 0.15)
				(type solid)
			)
			(layer "B.Fab")
		)
		(fp_line
			(start -0.494 -0.248)
			(end -0.494 0.25)
			(stroke
				(width 0.15)
				(type solid)
			)
			(layer "B.Fab")
		)
		(fp_line
			(start 0.504 0.25)
			(end 0.504 -0.248)
			(stroke
				(width 0.15)
				(type solid)
			)
			(layer "B.Fab")
		)
		(fp_line
			(start -0.494 0.25)
			(end 0.504 0.25)
			(stroke
				(width 0.15)
				(type solid)
			)
			(layer "B.Fab")
		)
		(pad "1" smd roundrect
			(at -0.48 0 90)
			(size 0.59 0.64)
			(layers "B.Cu" "B.Mask" "B.Paste")
			(roundrect_rratio 0.25)
			(net 143 "/Power supply/VREG_1V2")
			(pintype "passive")
		)
		(pad "2" smd roundrect
			(at 0.48 0 90)
			(size 0.59 0.64)
			(layers "B.Cu" "B.Mask" "B.Paste")
			(roundrect_rratio 0.25)
			(net 1 "GND")
			(pintype "passive")
		)
	)
	(footprint "antmicro-footprints:C_0402_1005Metric"
		(layer "B.Cu")
		(at 205.5 127 -90)
		(descr "Capacitor SMD 0402")
		(tags "capacitor SMD 0402")
		(property "Reference" "C14"
			(at -31.025 -28.65 90)
			(layer "B.SilkS")
			(effects
				(font
					(size 0.7 0.7)
					(thickness 0.15)
				)
				(justify left bottom mirror)
			)
		)
		(property "Value" "C_100n_0402"
			(at 0 -1.169 90)
			(layer "B.Fab")
			(effects
				(font
					(size 0.7 0.7)
					(thickness 0.15)
				)
				(justify left bottom mirror)
			)
		)
		(property "Description" "SMD Multilayer Ceramic Capacitor, 0.1 µF, 50 V, 0402 [1005 Metric], ± 10%, X5R, GRM Series"
			(at 0 0 270)
			(layer "F.Fab")
			(hide yes)
			(effects
				(font
					(size 1.27 1.27)
					(thickness 0.15)
				)
			)
		)
		(property "Author" "Antmicro"
			(at 78.5 332.5 0)
			(layer "B.Fab")
			(hide yes)
			(effects
				(font
					(size 1 1)
					(thickness 0.15)
				)
				(justify mirror)
			)
		)
		(property "Dielectric" "X5R"
			(at 78.5 332.5 0)
			(layer "B.Fab")
			(hide yes)
			(effects
				(font
					(size 1 1)
					(thickness 0.15)
				)
				(justify mirror)
			)
		)
		(property "License" "Apache-2.0"
			(at 78.5 332.5 0)
			(layer "B.Fab")
			(hide yes)
			(effects
				(font
					(size 1 1)
					(thickness 0.15)
				)
				(justify mirror)
			)
		)
		(property "MPN" "GRM155R61H104KE14D"
			(at 78.5 332.5 0)
			(layer "B.Fab")
			(hide yes)
			(effects
				(font
					(size 1 1)
					(thickness 0.15)
				)
				(justify mirror)
			)
		)
		(property "Manufacturer" "Murata"
			(at 78.5 332.5 0)
			(layer "B.Fab")
			(hide yes)
			(effects
				(font
					(size 1 1)
					(thickness 0.15)
				)
				(justify mirror)
			)
		)
		(property "Val" "100n"
			(at 78.5 332.5 0)
			(layer "B.Fab")
			(hide yes)
			(effects
				(font
					(size 1 1)
					(thickness 0.15)
				)
				(justify mirror)
			)
		)
		(property "Voltage" "50V"
			(at 78.5 332.5 0)
			(layer "B.Fab")
			(hide yes)
			(effects
				(font
					(size 1 1)
					(thickness 0.15)
				)
				(justify mirror)
			)
		)
		(sheetname "FPGA Bank 14 & 15")
		(sheetfile "fpga-bank-14-15.kicad_sch")
		(attr smd)
		(fp_rect
			(start -0.925 0.47)
			(end 0.925 -0.47)
			(stroke
				(width 0.05)
				(type default)
			)
			(fill no)
			(layer "B.CrtYd")
		)
		(fp_line
			(start -0.494 0.25)
			(end 0.504 0.25)
			(stroke
				(width 0.15)
				(type solid)
			)
			(layer "B.Fab")
		)
		(fp_line
			(start 0.504 0.25)
			(end 0.504 -0.248)
			(stroke
				(width 0.15)
				(type solid)
			)
			(layer "B.Fab")
		)
		(fp_line
			(start -0.494 -0.248)
			(end -0.494 0.25)
			(stroke
				(width 0.15)
				(type solid)
			)
			(layer "B.Fab")
		)
		(fp_line
			(start 0.504 -0.248)
			(end -0.494 -0.248)
			(stroke
				(width 0.15)
				(type solid)
			)
			(layer "B.Fab")
		)
		(pad "1" smd roundrect
			(at -0.48 0 270)
			(size 0.59 0.64)
			(layers "B.Cu" "B.Mask" "B.Paste")
			(roundrect_rratio 0.25)
			(net 1 "GND")
			(pintype "passive")
		)
		(pad "2" smd roundrect
			(at 0.48 0 270)
			(size 0.59 0.64)
			(layers "B.Cu" "B.Mask" "B.Paste")
			(roundrect_rratio 0.25)
			(net 2 "VCC_USR_A")
			(pintype "passive")
		)
	)
	(footprint "antmicro-footprints:C_0402_1005Metric"
		(layer "B.Cu")
		(at 174.649999 142.199999 -90)
		(descr "Capacitor SMD 0402")
		(tags "capacitor SMD 0402")
		(property "Reference" "C389"
			(at -1.424999 -1.300001 90)
			(layer "B.SilkS")
			(effects
				(font
					(size 0.7 0.7)
					(thickness 0.15)
				)
				(justify left bottom mirror)
			)
		)
		(property "Value" "C_100n_0402"
			(at 0 -1.169 90)
			(layer "B.Fab")
			(effects
				(font
					(size 0.7 0.7)
					(thickness 0.15)
				)
				(justify left bottom mirror)
			)
		)
		(property "Description" "SMD Multilayer Ceramic Capacitor, 0.1 µF, 50 V, 0402 [1005 Metric], ± 10%, X5R, GRM Series"
			(at 0 0 270)
			(layer "F.Fab")
			(hide yes)
			(effects
				(font
					(size 1.27 1.27)
					(thickness 0.15)
				)
			)
		)
		(property "Author" "Antmicro"
			(at 32.45 316.849998 0)
			(layer "B.Fab")
			(hide yes)
			(effects
				(font
					(size 1 1)
					(thickness 0.15)
				)
				(justify mirror)
			)
		)
		(property "Dielectric" "X5R"
			(at 32.45 316.849998 0)
			(layer "B.Fab")
			(hide yes)
			(effects
				(font
					(size 1 1)
					(thickness 0.15)
				)
				(justify mirror)
			)
		)
		(property "License" "Apache-2.0"
			(at 32.45 316.849998 0)
			(layer "B.Fab")
			(hide yes)
			(effects
				(font
					(size 1 1)
					(thickness 0.15)
				)
				(justify mirror)
			)
		)
		(property "MPN" "GRM155R61H104KE14D"
			(at 32.45 316.849998 0)
			(layer "B.Fab")
			(hide yes)
			(effects
				(font
					(size 1 1)
					(thickness 0.15)
				)
				(justify mirror)
			)
		)
		(property "Manufacturer" "Murata"
			(at 32.45 316.849998 0)
			(layer "B.Fab")
			(hide yes)
			(effects
				(font
					(size 1 1)
					(thickness 0.15)
				)
				(justify mirror)
			)
		)
		(property "Val" "100n"
			(at 32.45 316.849998 0)
			(layer "B.Fab")
			(hide yes)
			(effects
				(font
					(size 1 1)
					(thickness 0.15)
				)
				(justify mirror)
			)
		)
		(property "Voltage" "50V"
			(at 32.45 316.849998 0)
			(layer "B.Fab")
			(hide yes)
			(effects
				(font
					(size 1 1)
					(thickness 0.15)
				)
				(justify mirror)
			)
		)
		(sheetname "DRAM + SRAM")
		(sheetfile "ram.kicad_sch")
		(attr smd)
		(fp_rect
			(start -0.925 0.47)
			(end 0.925 -0.47)
			(stroke
				(width 0.05)
				(type default)
			)
			(fill no)
			(layer "B.CrtYd")
		)
		(fp_line
			(start -0.494 0.25)
			(end 0.504 0.25)
			(stroke
				(width 0.15)
				(type solid)
			)
			(layer "B.Fab")
		)
		(fp_line
			(start 0.504 0.25)
			(end 0.504 -0.248)
			(stroke
				(width 0.15)
				(type solid)
			)
			(layer "B.Fab")
		)
		(fp_line
			(start -0.494 -0.248)
			(end -0.494 0.25)
			(stroke
				(width 0.15)
				(type solid)
			)
			(layer "B.Fab")
		)
		(fp_line
			(start 0.504 -0.248)
			(end -0.494 -0.248)
			(stroke
				(width 0.15)
				(type solid)
			)
			(layer "B.Fab")
		)
		(pad "1" smd roundrect
			(at -0.48 0 270)
			(size 0.59 0.64)
			(layers "B.Cu" "B.Mask" "B.Paste")
			(roundrect_rratio 0.25)
			(net 1 "GND")
			(pintype "passive")
		)
		(pad "2" smd roundrect
			(at 0.48 0 270)
			(size 0.59 0.64)
			(layers "B.Cu" "B.Mask" "B.Paste")
			(roundrect_rratio 0.25)
			(net 25 "+1V35")
			(pintype "passive")
		)
	)
	(footprint "antmicro-footprints:C_0402_1005Metric"
		(layer "B.Cu")
		(at 157.5125 173.685 -90)
		(descr "Capacitor SMD 0402")
		(tags "capacitor SMD 0402")
		(property "Reference" "C316"
			(at 0.751 -0.3875 90)
			(layer "B.SilkS")
			(effects
				(font
					(size 0.7 0.7)
					(thickness 0.15)
				)
				(justify left bottom mirror)
			)
		)
		(property "Value" "C_1u_0402"
			(at 0 -1.4 90)
			(layer "B.Fab")
			(effects
				(font
					(size 0.7 0.7)
					(thickness 0.15)
				)
				(justify left bottom mirror)
			)
		)
		(property "Description" "SMD Multilayer Ceramic Capacitor, 1 µF, 10 V, 0402 [1005 Metric], ± 10%, X6S, C"
			(at 0 0 270)
			(layer "F.Fab")
			(hide yes)
			(effects
				(font
					(size 1.27 1.27)
					(thickness 0.15)
				)
			)
		)
		(property "Author" "Antmicro"
			(at -16.1725 331.1975 0)
			(layer "B.Fab")
			(hide yes)
			(effects
				(font
					(size 1 1)
					(thickness 0.15)
				)
				(justify mirror)
			)
		)
		(property "Dielectric" ""
			(at -16.1725 331.1975 0)
			(layer "B.Fab")
			(hide yes)
			(effects
				(font
					(size 1 1)
					(thickness 0.15)
				)
				(justify mirror)
			)
		)
		(property "License" "Apache-2.0"
			(at -16.1725 331.1975 0)
			(layer "B.Fab")
			(hide yes)
			(effects
				(font
					(size 1 1)
					(thickness 0.15)
				)
				(justify mirror)
			)
		)
		(property "MPN" "C1005X6S1A105K050BC"
			(at -16.1725 331.1975 0)
			(layer "B.Fab")
			(hide yes)
			(effects
				(font
					(size 1 1)
					(thickness 0.15)
				)
				(justify mirror)
			)
		)
		(property "Manufacturer" "TDK"
			(at -16.1725 331.1975 0)
			(layer "B.Fab")
			(hide yes)
			(effects
				(font
					(size 1 1)
					(thickness 0.15)
				)
				(justify mirror)
			)
		)
		(property "Val" "1u"
			(at -16.1725 331.1975 0)
			(layer "B.Fab")
			(hide yes)
			(effects
				(font
					(size 1 1)
					(thickness 0.15)
				)
				(justify mirror)
			)
		)
		(property "Voltage" ""
			(at -16.1725 331.1975 0)
			(layer "B.Fab")
			(hide yes)
			(effects
				(font
					(size 1 1)
					(thickness 0.15)
				)
				(justify mirror)
			)
		)
		(sheetname "DC-DC Converters")
		(sheetfile "dc-dc.kicad_sch")
		(attr smd)
		(fp_rect
			(start -0.925 0.47)
			(end 0.925 -0.47)
			(stroke
				(width 0.05)
				(type default)
			)
			(fill no)
			(layer "B.CrtYd")
		)
		(fp_line
			(start -0.494 0.25)
			(end 0.504 0.25)
			(stroke
				(width 0.15)
				(type solid)
			)
			(layer "B.Fab")
		)
		(fp_line
			(start 0.504 0.25)
			(end 0.504 -0.248)
			(stroke
				(width 0.15)
				(type solid)
			)
			(layer "B.Fab")
		)
		(fp_line
			(start -0.494 -0.248)
			(end -0.494 0.25)
			(stroke
				(width 0.15)
				(type solid)
			)
			(layer "B.Fab")
		)
		(fp_line
			(start 0.504 -0.248)
			(end -0.494 -0.248)
			(stroke
				(width 0.15)
				(type solid)
			)
			(layer "B.Fab")
		)
		(pad "1" smd roundrect
			(at -0.48 0 270)
			(size 0.59 0.64)
			(layers "B.Cu" "B.Mask" "B.Paste")
			(roundrect_rratio 0.25)
			(net 1 "GND")
			(pintype "passive")
		)
		(pad "2" smd roundrect
			(at 0.48 0 270)
			(size 0.59 0.64)
			(layers "B.Cu" "B.Mask" "B.Paste")
			(roundrect_rratio 0.25)
			(net 731 "/DC-DC Converters/QDCDC1_VCC")
			(pintype "passive")
		)
	)
	(footprint "antmicro-footprints:R_0402_1005Metric"
		(layer "B.Cu")
		(at 242.501 139.1 180)
		(descr "Resistor SMD 0402")
		(tags "resistor SMD 0402")
		(property "Reference" "R163"
			(at 0.726 -0.4 0)
			(layer "B.SilkS")
			(effects
				(font
					(size 0.7 0.7)
					(thickness 0.15)
				)
				(justify left bottom mirror)
			)
		)
		(property "Value" "R_33R_0402"
			(at 0 -1.4 0)
			(layer "B.Fab")
			(effects
				(font
					(size 0.7 0.7)
					(thickness 0.15)
				)
				(justify left bottom mirror)
			)
		)
		(property "Description" "SMD Chip Resistor, 33 ohm, ± 1%, 62.5 mW, 0402 [1005 Metric], Thick Film, General Purpose"
			(at 0 0 180)
			(layer "F.Fab")
			(hide yes)
			(effects
				(font
					(size 1.27 1.27)
					(thickness 0.15)
				)
			)
		)
		(property "Author" "Antmicro"
			(at 485.002 278.2 0)
			(layer "B.Fab")
			(hide yes)
			(effects
				(font
					(size 1 1)
					(thickness 0.15)
				)
				(justify mirror)
			)
		)
		(property "License" "Apache-2.0"
			(at 485.002 278.2 0)
			(layer "B.Fab")
			(hide yes)
			(effects
				(font
					(size 1 1)
					(thickness 0.15)
				)
				(justify mirror)
			)
		)
		(property "MPN" "CR0402-FX-33R0GLF"
			(at 485.002 278.2 0)
			(layer "B.Fab")
			(hide yes)
			(effects
				(font
					(size 1 1)
					(thickness 0.15)
				)
				(justify mirror)
			)
		)
		(property "Manufacturer" "Bourns"
			(at 485.002 278.2 0)
			(layer "B.Fab")
			(hide yes)
			(effects
				(font
					(size 1 1)
					(thickness 0.15)
				)
				(justify mirror)
			)
		)
		(property "Tolerance" "1%"
			(at 485.002 278.2 0)
			(layer "B.Fab")
			(hide yes)
			(effects
				(font
					(size 1 1)
					(thickness 0.15)
				)
				(justify mirror)
			)
		)
		(property "Val" "33R"
			(at 485.002 278.2 0)
			(layer "B.Fab")
			(hide yes)
			(effects
				(font
					(size 1 1)
					(thickness 0.15)
				)
				(justify mirror)
			)
		)
		(sheetname "USB PHY")
		(sheetfile "usb-phy.kicad_sch")
		(attr smd)
		(fp_rect
			(start -0.925 0.47)
			(end 0.925 -0.47)
			(stroke
				(width 0.05)
				(type default)
			)
			(fill no)
			(layer "B.CrtYd")
		)
		(fp_rect
			(start -0.5 0.25)
			(end 0.5 -0.25)
			(stroke
				(width 0.15)
				(type solid)
			)
			(fill no)
			(layer "B.Fab")
		)
		(pad "1" smd roundrect
			(at -0.48 0 180)
			(size 0.59 0.64)
			(layers "B.Cu" "B.Mask" "B.Paste")
			(roundrect_rratio 0.25)
			(net 923 "/USB PHY/FTDI_UART1_TX")
			(pintype "passive")
		)
		(pad "2" smd roundrect
			(at 0.48 0 180)
			(size 0.59 0.64)
			(layers "B.Cu" "B.Mask" "B.Paste")
			(roundrect_rratio 0.25)
			(net 45 "/FPGA Bank 12 & 13/UART1.RX")
			(pintype "passive")
		)
	)
)
